FILE_TYPE = CONNECTIVITY;
{Allegro Design Entry HDL 17.2-2016 S081 (4005846) 1/11/2022}
"PAGE_NUMBER" = 43;
0"NC";
1"M_G_CPU1_SA_DQ<31:0>";
2"M_G_CPU1_SB_DQ<31:0>";
3"M_G_CPU1_SA_CB<7:0>";
4"M_G_CPU1_SB_CB<7:0>";
5"M_G_CPU1_SA_DQS_DP<9:0>";
6"M_G_CPU1_SB_DQS_DP<9:0>";
7"M_G_CPU1_SA_CA<6:0>";
8"M_G_CPU1_SB_CA<6:0>";
9"M_G_CPU1_SA_DQS_DN<9:0>";
10"M_G_CPU1_SB_DQS_DN<9:0>";
11"M_G_CPU1_ALERT_N";
12"TP_M_G_CPU1_SA_TEST39G";
13"M_G_CPU1_ALERT_R_N";
14"M_G_CPU1_CLK_DN<0>";
15"M_G_CPU1_CLK_DP<0>";
16"M_G_CPU1_SA_CS_N<0>";
17"M_G_CPU1_SA_CS_N<1>";
18"M_G_CPU1_SA_PAR";
19"M_G_CPU1_SA_RSP<0>";
20"M_G_CPU1_SB_CS_N<0>";
21"M_G_CPU1_SB_CS_N<1>";
22"M_G_CPU1_SB_RSP<0>";
23"M_G_CPU1_SB_PAR";
24"M_G_CPU1_RESET_N";
25"M_G_CPU1_SB_CA<6>";
26"M_G_CPU1_SA_CA<6>";
27"M_G_CPU1_SB_CA<5>";
28"M_G_CPU1_SA_CA<5>";
29"M_G_CPU1_SB_CA<4>";
30"M_G_CPU1_SA_CA<4>";
31"M_G_CPU1_SB_CA<3>";
32"M_G_CPU1_SA_CA<3>";
33"M_G_CPU1_SB_CA<2>";
34"M_G_CPU1_SA_CA<2>";
35"M_G_CPU1_SB_CA<1>";
36"M_G_CPU1_SA_CA<1>";
37"M_G_CPU1_SB_CA<0>";
38"M_G_CPU1_SA_CA<0>";
39"M_G_CPU1_SB_DQS_DN<9>";
40"M_G_CPU1_SB_DQS_DP<9>";
41"M_G_CPU1_SB_DQS_DP<4>";
42"M_G_CPU1_SB_DQS_DN<8>";
43"M_G_CPU1_SB_DQS_DP<3>";
44"M_G_CPU1_SB_DQS_DN<7>";
45"M_G_CPU1_SB_DQS_DP<2>";
46"M_G_CPU1_SB_DQS_DN<6>";
47"M_G_CPU1_SB_DQS_DP<1>";
48"M_G_CPU1_SB_DQS_DN<5>";
49"M_G_CPU1_SB_DQS_DP<0>";
50"M_G_CPU1_SB_DQS_DN<4>";
51"M_G_CPU1_SA_DQS_DN<9>";
52"M_G_CPU1_SB_DQS_DN<3>";
53"M_G_CPU1_SB_DQS_DN<2>";
54"M_G_CPU1_SB_DQS_DN<1>";
55"M_G_CPU1_SB_DQS_DN<0>";
56"M_G_CPU1_SB_DQS_DP<8>";
57"M_G_CPU1_SB_DQS_DP<7>";
58"M_G_CPU1_SB_DQS_DP<6>";
59"M_G_CPU1_SB_DQS_DP<5>";
60"M_G_CPU1_SA_DQS_DP<9>";
61"M_G_CPU1_SA_DQS_DP<8>";
62"M_G_CPU1_SA_DQS_DP<7>";
63"M_G_CPU1_SA_DQS_DP<6>";
64"M_G_CPU1_SA_DQS_DP<5>";
65"M_G_CPU1_SA_DQS_DP<4>";
66"M_G_CPU1_SA_DQS_DN<8>";
67"M_G_CPU1_SA_DQS_DP<3>";
68"M_G_CPU1_SA_DQS_DN<7>";
69"M_G_CPU1_SA_DQS_DP<2>";
70"M_G_CPU1_SA_DQS_DN<6>";
71"M_G_CPU1_SA_DQS_DP<1>";
72"M_G_CPU1_SA_DQS_DN<5>";
73"M_G_CPU1_SA_DQS_DP<0>";
74"M_G_CPU1_SA_DQS_DN<4>";
75"M_G_CPU1_SA_DQS_DN<3>";
76"M_G_CPU1_SA_DQS_DN<2>";
77"M_G_CPU1_SA_DQS_DN<1>";
78"M_G_CPU1_SA_DQS_DN<0>";
79"M_G_CPU1_SB_CB<7>";
80"M_G_CPU1_SB_CB<6>";
81"M_G_CPU1_SB_CB<5>";
82"M_G_CPU1_SB_CB<4>";
83"M_G_CPU1_SB_CB<3>";
84"M_G_CPU1_SB_CB<2>";
85"M_G_CPU1_SB_CB<1>";
86"M_G_CPU1_SB_CB<0>";
87"M_G_CPU1_SA_CB<1>";
88"M_G_CPU1_SA_CB<0>";
89"M_G_CPU1_SB_DQ<29>";
90"M_G_CPU1_SB_DQ<28>";
91"M_G_CPU1_SB_DQ<27>";
92"M_G_CPU1_SB_DQ<26>";
93"M_G_CPU1_SB_DQ<25>";
94"M_G_CPU1_SB_DQ<24>";
95"M_G_CPU1_SB_DQ<23>";
96"M_G_CPU1_SB_DQ<22>";
97"M_G_CPU1_SA_CB<7>";
98"M_G_CPU1_SA_CB<6>";
99"M_G_CPU1_SB_DQ<31>";
100"M_G_CPU1_SA_CB<5>";
101"M_G_CPU1_SB_DQ<30>";
102"M_G_CPU1_SA_CB<4>";
103"M_G_CPU1_SA_CB<3>";
104"M_G_CPU1_SA_CB<2>";
105"M_G_CPU1_SB_DQ<19>";
106"M_G_CPU1_SB_DQ<18>";
107"M_G_CPU1_SB_DQ<17>";
108"M_G_CPU1_SB_DQ<16>";
109"M_G_CPU1_SB_DQ<15>";
110"M_G_CPU1_SB_DQ<14>";
111"M_G_CPU1_SB_DQ<9>";
112"M_G_CPU1_SB_DQ<13>";
113"M_G_CPU1_SB_DQ<8>";
114"M_G_CPU1_SB_DQ<12>";
115"M_G_CPU1_SB_DQ<7>";
116"M_G_CPU1_SB_DQ<11>";
117"M_G_CPU1_SB_DQ<6>";
118"M_G_CPU1_SB_DQ<10>";
119"M_G_CPU1_SB_DQ<21>";
120"M_G_CPU1_SB_DQ<5>";
121"M_G_CPU1_SB_DQ<20>";
122"M_G_CPU1_SB_DQ<4>";
123"M_G_CPU1_SA_DQ<21>";
124"M_G_CPU1_SB_DQ<0>";
125"M_G_CPU1_SA_DQ<20>";
126"M_G_CPU1_SA_DQ<31>";
127"M_G_CPU1_SA_DQ<30>";
128"M_G_CPU1_SA_DQ<19>";
129"M_G_CPU1_SA_DQ<18>";
130"M_G_CPU1_SA_DQ<29>";
131"M_G_CPU1_SA_DQ<17>";
132"M_G_CPU1_SA_DQ<28>";
133"M_G_CPU1_SA_DQ<27>";
134"M_G_CPU1_SA_DQ<26>";
135"M_G_CPU1_SA_DQ<25>";
136"M_G_CPU1_SA_DQ<24>";
137"M_G_CPU1_SB_DQ<3>";
138"M_G_CPU1_SA_DQ<23>";
139"M_G_CPU1_SB_DQ<2>";
140"M_G_CPU1_SA_DQ<22>";
141"M_G_CPU1_SB_DQ<1>";
142"M_G_CPU1_SA_DQ<0>";
143"M_G_CPU1_SA_DQ<10>";
144"M_G_CPU1_SA_DQ<9>";
145"M_G_CPU1_SA_DQ<8>";
146"M_G_CPU1_SA_DQ<7>";
147"M_G_CPU1_SA_DQ<6>";
148"M_G_CPU1_SA_DQ<16>";
149"M_G_CPU1_SA_DQ<5>";
150"M_G_CPU1_SA_DQ<15>";
151"M_G_CPU1_SA_DQ<4>";
152"M_G_CPU1_SA_DQ<14>";
153"M_G_CPU1_SA_DQ<3>";
154"M_G_CPU1_SA_DQ<13>";
155"M_G_CPU1_SA_DQ<2>";
156"M_G_CPU1_SA_DQ<12>";
157"M_G_CPU1_SA_DQ<1>";
158"M_G_CPU1_SA_DQ<11>";
%"GENOA_SP5"
"7","(-4700,3675)","0","pure_quanta","I167";
;
LOCATION"U26"
$SEC"7"
CDS_SEC"7"
PART_TYPE"SMLF"
MATERIAL"IO"
VALUE"SOCKET6096_13568-001"
PART_NUMBER"DGA^6000030"
NEEDS_NO_SIZE"TRUE"
CDS_LMAN_SYM_OUTLINE"-650,2525,650,-2525"
CDS_LIB"pure_quanta";
"TEST39G"
$PN"BF4"12;
"MG1_CLK_L"
$PN"BG2"0;
"MG1_CLK_H"
$PN"BF2"0;
"MG0_CLK_L"
$PN"BD2"14;
"MG0_CLK_H"
$PN"BC2"15;
"MGA_PAR"
$PN"BC3"18;
"MGB_DQS_H9"
$PN"BV2"40;
"MGB_PAR"
$PN"BL3"23;
"MGA_CHECK1"
$PN"AK4"87;
"MGA_DATA0"
$PN"E2"142;
"MGA_DATA10"
$PN"M2"143;
"MGA_DATA21"
$PN"AB4"123;
"MGB_DATA0"
$PN"CB2"124;
"MGB_DQS_H4"
$PN"BY4"41;
"MGB_DQS_L8"
$PN"DC3"42;
"MGA_CHECK0"
$PN"AJ2"88;
"MGA_DATA20"
$PN"AA2"125;
"MGA_DATA31"
$PN"AJ3"126;
"MGA_DQS_H9"
$PN"AN3"60;
"MGB_DQS_H3"
$PN"DB2"43;
"MGB_DQS_L7"
$PN"CU3"44;
"MGA0_CS_L1"
$PN"AV4"17;
"MGA1_CS_L1"
$PN"AW3"0;
"MGA_DATA30"
$PN"AH2"127;
"MGA_DQS_H8"
$PN"AG3"61;
"MGB_DATA19"
$PN"CT4"105;
"MGB_DQS_H2"
$PN"CT2"45;
"MGB_DQS_L6"
$PN"CL3"46;
"MGA0_CS_L0"
$PN"AU2"16;
"MGA1_CS_L0"
$PN"AV2"0;
"MGA_DQS_H7"
$PN"AA3"62;
"MGB_DATA18"
$PN"CR2"106;
"MGB_DATA29"
$PN"DE3"89;
"MGB_DQS_H1"
$PN"CK2"47;
"MGB_DQS_L5"
$PN"CE3"48;
"MGA_DQS_H6"
$PN"R3"63;
"MGB_DATA17"
$PN"CR3"107;
"MGB_DATA28"
$PN"DD2"90;
"MGB_DQS_H0"
$PN"CD2"49;
"MGB_DQS_L4"
$PN"BW3"50;
"MGA_DQS_H5"
$PN"J3"64;
"MGA_DQS_L9"
$PN"AM4"51;
"MGB0_RSP_L"
$PN"BP2"22;
"MGB1_RSP_L"
$PN"BR2"0;
"MGB_CHECK7"
$PN"BV4"79;
"MGB_DATA16"
$PN"CP2"108;
"MGB_DATA27"
$PN"DB4"91;
"MGB_DQS_L3"
$PN"DC2"52;
"MGA_DQS_H4"
$PN"AL2"65;
"MGA_DQS_L8"
$PN"AF4"66;
"MGB_CA6"
$PN"BK2"25;
"MGB_CHECK6"
$PN"BU2"80;
"MGB_DATA15"
$PN"CP4"109;
"MGB_DATA26"
$PN"DA2"92;
"MGB_DQS_L2"
$PN"CU2"53;
"MGA_CA6"
$PN"BB4"26;
"MGA_DQS_H3"
$PN"AE2"67;
"MGA_DQS_L7"
$PN"Y4"68;
"MGB_CA5"
$PN"BK4"27;
"MGB_CHECK5"
$PN"BU3"81;
"MGB_DATA14"
$PN"CN2"110;
"MGB_DATA25"
$PN"DA3"93;
"MGB_DQS_L1"
$PN"CL2"54;
"MGA_CA5"
$PN"BB2"28;
"MGA_DATA9"
$PN"M4"144;
"MGA_DATA19"
$PN"W3"128;
"MGA_DQS_H2"
$PN"W2"69;
"MGA_DQS_L6"
$PN"P4"70;
"MGB_CA4"
$PN"BJ3"29;
"MGB_CHECK4"
$PN"BT2"82;
"MGB_DATA9"
$PN"CJ3"111;
"MGB_DATA13"
$PN"CN3"112;
"MGB_DATA24"
$PN"CY2"94;
"MGB_DQS_L0"
$PN"CE2"55;
"MGA_CA4"
$PN"BA2"30;
"MGA_DATA8"
$PN"L2"145;
"MGA_DATA18"
$PN"V2"129;
"MGA_DATA29"
$PN"AH4"130;
"MGA_DQS_H1"
$PN"N2"71;
"MGA_DQS_L5"
$PN"H4"72;
"MGB_CA3"
$PN"BJ2"31;
"MGB_CHECK3"
$PN"CB4"83;
"MGB_DATA8"
$PN"CH2"113;
"MGB_DATA12"
$PN"CM2"114;
"MGB_DATA23"
$PN"CY4"95;
"MGA_CA3"
$PN"BA3"32;
"MGA_DATA7"
$PN"L3"146;
"MGA_DATA17"
$PN"V4"131;
"MGA_DATA28"
$PN"AG2"132;
"MGA_DQS_H0"
$PN"G2"73;
"MGA_DQS_L4"
$PN"AM2"74;
"MGB_CA2"
$PN"BH2"33;
"MGB_CHECK2"
$PN"CA2"84;
"MGB_DATA7"
$PN"CH4"115;
"MGB_DATA11"
$PN"CK4"116;
"MGB_DATA22"
$PN"CW2"96;
"MGA0_RSP_L"
$PN"BN3"19;
"MGA1_RSP_L"
$PN"BP4"0;
"MGA_CA2"
$PN"AY4"34;
"MGA_CHECK7"
$PN"AR3"97;
"MGA_DATA6"
$PN"K2"147;
"MGA_DATA16"
$PN"U2"148;
"MGA_DATA27"
$PN"AE3"133;
"MGA_DQS_L3"
$PN"AF2"75;
"MGB_CA1"
$PN"BH4"35;
"MGB_CHECK1"
$PN"CA3"85;
"MGB_DATA6"
$PN"CG2"117;
"MGB_DATA10"
$PN"CJ2"118;
"MGB_DATA21"
$PN"CW3"119;
"MGA_CA1"
$PN"AY2"36;
"MGA_CHECK6"
$PN"AP2"98;
"MGA_DATA5"
$PN"K4"149;
"MGA_DATA15"
$PN"U3"150;
"MGA_DATA26"
$PN"AD2"134;
"MGA_DQS_L2"
$PN"Y2"76;
"MGB_CA0"
$PN"BG3"37;
"MGB_CHECK0"
$PN"BY2"86;
"MGB_DATA5"
$PN"CG3"120;
"MGB_DATA20"
$PN"CV2"121;
"MGB_DATA31"
$PN"DF2"99;
"MGA_CA0"
$PN"AW2"38;
"MGA_CHECK5"
$PN"AP4"100;
"MGA_DATA4"
$PN"J2"151;
"MGA_DATA14"
$PN"T2"152;
"MGA_DATA25"
$PN"AD4"135;
"MGA_DQS_L1"
$PN"P2"77;
"MGB0_CS_L1"
$PN"BN2"21;
"MGB1_CS_L1"
$PN"BM2"0;
"MGB_DATA4"
$PN"CF2"122;
"MGB_DATA30"
$PN"DE2"101;
"MGB_DQS_H8"
$PN"DD4"56;
"MGA_CHECK4"
$PN"AN2"102;
"MGA_DATA3"
$PN"G3"153;
"MGA_DATA13"
$PN"T4"154;
"MGA_DATA24"
$PN"AC2"136;
"MGA_DQS_L0"
$PN"H2"78;
"MGB0_CS_L0"
$PN"BM4"20;
"MGB1_CS_L0"
$PN"BL2"0;
"MGB_DATA3"
$PN"CD4"137;
"MGB_DQS_H7"
$PN"CV4"57;
"MGA_CHECK3"
$PN"AL3"103;
"MGA_DATA2"
$PN"F2"155;
"MGA_DATA12"
$PN"R2"156;
"MGA_DATA23"
$PN"AC3"138;
"MGB_DATA2"
$PN"CC2"139;
"MGB_DQS_H6"
$PN"CM4"58;
"MGA_CHECK2"
$PN"AK2"104;
"MGA_DATA1"
$PN"F4"157;
"MGA_DATA11"
$PN"N3"158;
"MGA_DATA22"
$PN"AB2"140;
"MGB_DATA1"
$PN"CC3"141;
"MGB_DQS_H5"
$PN"CF4"59;
"MGB_DQS_L9"
$PN"BW2"39;
"MG_RESET_L"
$PN"AT2"24;
"MG_ALERT_L"
$PN"AR2"13;
%"TAP"
"1","(-3425,6050)","0","mstr_standard","I170";
;
CDS_LIB"mstr_standard"
BODY_TYPE"PLUMBING"
HDL_TAP"TRUE";
"B \NAC \NWC"1;
"S \NAC"
BN"0"142;
%"TAP"
"1","(-3425,6000)","0","mstr_standard","I171";
;
CDS_LIB"mstr_standard"
BODY_TYPE"PLUMBING"
HDL_TAP"TRUE";
"B \NAC \NWC"1;
"S \NAC"
BN"1"157;
%"TAP"
"1","(-3425,5900)","0","mstr_standard","I172";
;
CDS_LIB"mstr_standard"
BODY_TYPE"PLUMBING"
HDL_TAP"TRUE";
"B \NAC \NWC"1;
"S \NAC"
BN"3"153;
%"TAP"
"1","(-3425,5950)","0","mstr_standard","I173";
;
CDS_LIB"mstr_standard"
BODY_TYPE"PLUMBING"
HDL_TAP"TRUE";
"B \NAC \NWC"1;
"S \NAC"
BN"2"155;
%"TAP"
"1","(-3425,5850)","0","mstr_standard","I174";
;
CDS_LIB"mstr_standard"
BODY_TYPE"PLUMBING"
HDL_TAP"TRUE";
"B \NAC \NWC"1;
"S \NAC"
BN"4"151;
%"TAP"
"1","(-3425,5800)","0","mstr_standard","I175";
;
CDS_LIB"mstr_standard"
BODY_TYPE"PLUMBING"
HDL_TAP"TRUE";
"B \NAC \NWC"1;
"S \NAC"
BN"5"149;
%"TAP"
"1","(-3425,5750)","0","mstr_standard","I176";
;
CDS_LIB"mstr_standard"
BODY_TYPE"PLUMBING"
HDL_TAP"TRUE";
"B \NAC \NWC"1;
"S \NAC"
BN"6"147;
%"TAP"
"1","(-3425,5700)","0","mstr_standard","I177";
;
CDS_LIB"mstr_standard"
BODY_TYPE"PLUMBING"
HDL_TAP"TRUE";
"B \NAC \NWC"1;
"S \NAC"
BN"7"146;
%"TAP"
"1","(-3425,5600)","0","mstr_standard","I178";
;
CDS_LIB"mstr_standard"
BODY_TYPE"PLUMBING"
HDL_TAP"TRUE";
"B \NAC \NWC"1;
"S \NAC"
BN"8"145;
%"TAP"
"1","(-3425,5550)","0","mstr_standard","I179";
;
CDS_LIB"mstr_standard"
BODY_TYPE"PLUMBING"
HDL_TAP"TRUE";
"B \NAC \NWC"1;
"S \NAC"
BN"9"144;
%"TAP"
"1","(-3425,5500)","0","mstr_standard","I180";
;
CDS_LIB"mstr_standard"
BODY_TYPE"PLUMBING"
HDL_TAP"TRUE";
"B \NAC \NWC"1;
"S \NAC"
BN"10"143;
%"TAP"
"1","(-3425,5450)","0","mstr_standard","I181";
;
CDS_LIB"mstr_standard"
BODY_TYPE"PLUMBING"
HDL_TAP"TRUE";
"B \NAC \NWC"1;
"S \NAC"
BN"11"158;
%"TAP"
"1","(-3425,5400)","0","mstr_standard","I182";
;
CDS_LIB"mstr_standard"
BODY_TYPE"PLUMBING"
HDL_TAP"TRUE";
"B \NAC \NWC"1;
"S \NAC"
BN"12"156;
%"TAP"
"1","(-3425,5350)","0","mstr_standard","I183";
;
CDS_LIB"mstr_standard"
BODY_TYPE"PLUMBING"
HDL_TAP"TRUE";
"B \NAC \NWC"1;
"S \NAC"
BN"13"154;
%"TAP"
"1","(-3425,5250)","0","mstr_standard","I184";
;
CDS_LIB"mstr_standard"
BODY_TYPE"PLUMBING"
HDL_TAP"TRUE";
"B \NAC \NWC"1;
"S \NAC"
BN"15"150;
%"TAP"
"1","(-3425,5300)","0","mstr_standard","I185";
;
CDS_LIB"mstr_standard"
BODY_TYPE"PLUMBING"
HDL_TAP"TRUE";
"B \NAC \NWC"1;
"S \NAC"
BN"14"152;
%"TAP"
"1","(-3425,5150)","0","mstr_standard","I186";
;
CDS_LIB"mstr_standard"
BODY_TYPE"PLUMBING"
HDL_TAP"TRUE";
"B \NAC \NWC"1;
"S \NAC"
BN"16"148;
%"TAP"
"1","(-3425,5100)","0","mstr_standard","I187";
;
CDS_LIB"mstr_standard"
BODY_TYPE"PLUMBING"
HDL_TAP"TRUE";
"B \NAC \NWC"1;
"S \NAC"
BN"17"131;
%"TAP"
"1","(-3425,5000)","0","mstr_standard","I188";
;
CDS_LIB"mstr_standard"
BODY_TYPE"PLUMBING"
HDL_TAP"TRUE";
"B \NAC \NWC"1;
"S \NAC"
BN"19"128;
%"TAP"
"1","(-3425,5050)","0","mstr_standard","I189";
;
CDS_LIB"mstr_standard"
BODY_TYPE"PLUMBING"
HDL_TAP"TRUE";
"B \NAC \NWC"1;
"S \NAC"
BN"18"129;
%"TAP"
"1","(-3425,4950)","0","mstr_standard","I190";
;
CDS_LIB"mstr_standard"
BODY_TYPE"PLUMBING"
HDL_TAP"TRUE";
"B \NAC \NWC"1;
"S \NAC"
BN"20"125;
%"TAP"
"1","(-3425,4900)","0","mstr_standard","I191";
;
CDS_LIB"mstr_standard"
BODY_TYPE"PLUMBING"
HDL_TAP"TRUE";
"B \NAC \NWC"1;
"S \NAC"
BN"21"123;
%"TAP"
"1","(-3425,4850)","0","mstr_standard","I192";
;
CDS_LIB"mstr_standard"
BODY_TYPE"PLUMBING"
HDL_TAP"TRUE";
"B \NAC \NWC"1;
"S \NAC"
BN"22"140;
%"TAP"
"1","(-3425,4800)","0","mstr_standard","I193";
;
CDS_LIB"mstr_standard"
BODY_TYPE"PLUMBING"
HDL_TAP"TRUE";
"B \NAC \NWC"1;
"S \NAC"
BN"23"138;
%"TAP"
"1","(-3425,4700)","0","mstr_standard","I194";
;
CDS_LIB"mstr_standard"
BODY_TYPE"PLUMBING"
HDL_TAP"TRUE";
"B \NAC \NWC"1;
"S \NAC"
BN"24"136;
%"TAP"
"1","(-3425,4650)","0","mstr_standard","I195";
;
CDS_LIB"mstr_standard"
BODY_TYPE"PLUMBING"
HDL_TAP"TRUE";
"B \NAC \NWC"1;
"S \NAC"
BN"25"135;
%"TAP"
"1","(-3425,4600)","0","mstr_standard","I196";
;
CDS_LIB"mstr_standard"
BODY_TYPE"PLUMBING"
HDL_TAP"TRUE";
"B \NAC \NWC"1;
"S \NAC"
BN"26"134;
%"TAP"
"1","(-3425,4550)","0","mstr_standard","I197";
;
CDS_LIB"mstr_standard"
BODY_TYPE"PLUMBING"
HDL_TAP"TRUE";
"B \NAC \NWC"1;
"S \NAC"
BN"27"133;
%"TAP"
"1","(-3425,4500)","0","mstr_standard","I198";
;
CDS_LIB"mstr_standard"
BODY_TYPE"PLUMBING"
HDL_TAP"TRUE";
"B \NAC \NWC"1;
"S \NAC"
BN"28"132;
%"TAP"
"1","(-3425,4450)","0","mstr_standard","I199";
;
CDS_LIB"mstr_standard"
BODY_TYPE"PLUMBING"
HDL_TAP"TRUE";
"B \NAC \NWC"1;
"S \NAC"
BN"29"130;
%"TAP"
"1","(-3425,4400)","0","mstr_standard","I200";
;
CDS_LIB"mstr_standard"
BODY_TYPE"PLUMBING"
HDL_TAP"TRUE";
"B \NAC \NWC"1;
"S \NAC"
BN"30"127;
%"TAP"
"1","(-3425,4350)","0","mstr_standard","I201";
;
CDS_LIB"mstr_standard"
BODY_TYPE"PLUMBING"
HDL_TAP"TRUE";
"B \NAC \NWC"1;
"S \NAC"
BN"31"126;
%"TAP"
"1","(-3425,4250)","0","mstr_standard","I202";
;
CDS_LIB"mstr_standard"
BODY_TYPE"PLUMBING"
HDL_TAP"TRUE";
"B \NAC \NWC"2;
"S \NAC"
BN"0"124;
%"TAP"
"1","(-3425,4200)","0","mstr_standard","I203";
;
CDS_LIB"mstr_standard"
BODY_TYPE"PLUMBING"
HDL_TAP"TRUE";
"B \NAC \NWC"2;
"S \NAC"
BN"1"141;
%"TAP"
"1","(-3425,4100)","0","mstr_standard","I204";
;
CDS_LIB"mstr_standard"
BODY_TYPE"PLUMBING"
HDL_TAP"TRUE";
"B \NAC \NWC"2;
"S \NAC"
BN"3"137;
%"TAP"
"1","(-3425,4150)","0","mstr_standard","I205";
;
CDS_LIB"mstr_standard"
BODY_TYPE"PLUMBING"
HDL_TAP"TRUE";
"B \NAC \NWC"2;
"S \NAC"
BN"2"139;
%"TAP"
"1","(-3425,4050)","0","mstr_standard","I207";
;
CDS_LIB"mstr_standard"
BODY_TYPE"PLUMBING"
HDL_TAP"TRUE";
"B \NAC \NWC"2;
"S \NAC"
BN"4"122;
%"TAP"
"1","(-3425,4000)","0","mstr_standard","I208";
;
CDS_LIB"mstr_standard"
BODY_TYPE"PLUMBING"
HDL_TAP"TRUE";
"B \NAC \NWC"2;
"S \NAC"
BN"5"120;
%"TAP"
"1","(-3425,3950)","0","mstr_standard","I209";
;
CDS_LIB"mstr_standard"
BODY_TYPE"PLUMBING"
HDL_TAP"TRUE";
"B \NAC \NWC"2;
"S \NAC"
BN"6"117;
%"TAP"
"1","(-3425,3900)","0","mstr_standard","I210";
;
CDS_LIB"mstr_standard"
BODY_TYPE"PLUMBING"
HDL_TAP"TRUE";
"B \NAC \NWC"2;
"S \NAC"
BN"7"115;
%"TAP"
"1","(-3425,3800)","0","mstr_standard","I211";
;
CDS_LIB"mstr_standard"
BODY_TYPE"PLUMBING"
HDL_TAP"TRUE";
"B \NAC \NWC"2;
"S \NAC"
BN"8"113;
%"TAP"
"1","(-3425,3750)","0","mstr_standard","I212";
;
CDS_LIB"mstr_standard"
BODY_TYPE"PLUMBING"
HDL_TAP"TRUE";
"B \NAC \NWC"2;
"S \NAC"
BN"9"111;
%"TAP"
"1","(-3425,3700)","0","mstr_standard","I213";
;
CDS_LIB"mstr_standard"
BODY_TYPE"PLUMBING"
HDL_TAP"TRUE";
"B \NAC \NWC"2;
"S \NAC"
BN"10"118;
%"TAP"
"1","(-3425,3650)","0","mstr_standard","I214";
;
CDS_LIB"mstr_standard"
BODY_TYPE"PLUMBING"
HDL_TAP"TRUE";
"B \NAC \NWC"2;
"S \NAC"
BN"11"116;
%"TAP"
"1","(-3425,3600)","0","mstr_standard","I215";
;
CDS_LIB"mstr_standard"
BODY_TYPE"PLUMBING"
HDL_TAP"TRUE";
"B \NAC \NWC"2;
"S \NAC"
BN"12"114;
%"TAP"
"1","(-3425,3550)","0","mstr_standard","I216";
;
CDS_LIB"mstr_standard"
BODY_TYPE"PLUMBING"
HDL_TAP"TRUE";
"B \NAC \NWC"2;
"S \NAC"
BN"13"112;
%"TAP"
"1","(-3425,3500)","0","mstr_standard","I217";
;
CDS_LIB"mstr_standard"
BODY_TYPE"PLUMBING"
HDL_TAP"TRUE";
"B \NAC \NWC"2;
"S \NAC"
BN"14"110;
%"TAP"
"1","(-3425,3450)","0","mstr_standard","I218";
;
CDS_LIB"mstr_standard"
BODY_TYPE"PLUMBING"
HDL_TAP"TRUE";
"B \NAC \NWC"2;
"S \NAC"
BN"15"109;
%"TAP"
"1","(-3425,3350)","0","mstr_standard","I219";
;
CDS_LIB"mstr_standard"
BODY_TYPE"PLUMBING"
HDL_TAP"TRUE";
"B \NAC \NWC"2;
"S \NAC"
BN"16"108;
%"TAP"
"1","(-3425,3300)","0","mstr_standard","I220";
;
CDS_LIB"mstr_standard"
BODY_TYPE"PLUMBING"
HDL_TAP"TRUE";
"B \NAC \NWC"2;
"S \NAC"
BN"17"107;
%"TAP"
"1","(-3425,3250)","0","mstr_standard","I221";
;
CDS_LIB"mstr_standard"
BODY_TYPE"PLUMBING"
HDL_TAP"TRUE";
"B \NAC \NWC"2;
"S \NAC"
BN"18"106;
%"TAP"
"1","(-3425,3200)","0","mstr_standard","I222";
;
CDS_LIB"mstr_standard"
BODY_TYPE"PLUMBING"
HDL_TAP"TRUE";
"B \NAC \NWC"2;
"S \NAC"
BN"19"105;
%"TAP"
"1","(-3425,3150)","0","mstr_standard","I223";
;
CDS_LIB"mstr_standard"
BODY_TYPE"PLUMBING"
HDL_TAP"TRUE";
"B \NAC \NWC"2;
"S \NAC"
BN"20"121;
%"TAP"
"1","(-3425,3100)","0","mstr_standard","I224";
;
CDS_LIB"mstr_standard"
BODY_TYPE"PLUMBING"
HDL_TAP"TRUE";
"B \NAC \NWC"2;
"S \NAC"
BN"21"119;
%"TAP"
"1","(-3425,3000)","0","mstr_standard","I225";
;
CDS_LIB"mstr_standard"
BODY_TYPE"PLUMBING"
HDL_TAP"TRUE";
"B \NAC \NWC"2;
"S \NAC"
BN"23"95;
%"TAP"
"1","(-3425,3050)","0","mstr_standard","I226";
;
CDS_LIB"mstr_standard"
BODY_TYPE"PLUMBING"
HDL_TAP"TRUE";
"B \NAC \NWC"2;
"S \NAC"
BN"22"96;
%"TAP"
"1","(-3425,2900)","0","mstr_standard","I227";
;
CDS_LIB"mstr_standard"
BODY_TYPE"PLUMBING"
HDL_TAP"TRUE";
"B \NAC \NWC"2;
"S \NAC"
BN"24"94;
%"TAP"
"1","(-3425,2850)","0","mstr_standard","I228";
;
CDS_LIB"mstr_standard"
BODY_TYPE"PLUMBING"
HDL_TAP"TRUE";
"B \NAC \NWC"2;
"S \NAC"
BN"25"93;
%"TAP"
"1","(-3425,2800)","0","mstr_standard","I229";
;
CDS_LIB"mstr_standard"
BODY_TYPE"PLUMBING"
HDL_TAP"TRUE";
"B \NAC \NWC"2;
"S \NAC"
BN"26"92;
%"TAP"
"1","(-3425,2700)","0","mstr_standard","I230";
;
CDS_LIB"mstr_standard"
BODY_TYPE"PLUMBING"
HDL_TAP"TRUE";
"B \NAC \NWC"2;
"S \NAC"
BN"28"90;
%"TAP"
"1","(-3425,2750)","0","mstr_standard","I231";
;
CDS_LIB"mstr_standard"
BODY_TYPE"PLUMBING"
HDL_TAP"TRUE";
"B \NAC \NWC"2;
"S \NAC"
BN"27"91;
%"TAP"
"1","(-3425,2650)","0","mstr_standard","I232";
;
CDS_LIB"mstr_standard"
BODY_TYPE"PLUMBING"
HDL_TAP"TRUE";
"B \NAC \NWC"2;
"S \NAC"
BN"29"89;
%"TAP"
"1","(-3425,2600)","0","mstr_standard","I233";
;
CDS_LIB"mstr_standard"
BODY_TYPE"PLUMBING"
HDL_TAP"TRUE";
"B \NAC \NWC"2;
"S \NAC"
BN"30"101;
%"TAP"
"1","(-3425,2550)","0","mstr_standard","I234";
;
CDS_LIB"mstr_standard"
BODY_TYPE"PLUMBING"
HDL_TAP"TRUE";
"B \NAC \NWC"2;
"S \NAC"
BN"31"99;
%"TAP"
"1","(-3425,2450)","0","mstr_standard","I235";
;
CDS_LIB"mstr_standard"
BODY_TYPE"PLUMBING"
HDL_TAP"TRUE";
"B \NAC \NWC"3;
"S \NAC"
BN"0"88;
%"TAP"
"1","(-3425,2400)","0","mstr_standard","I236";
;
CDS_LIB"mstr_standard"
BODY_TYPE"PLUMBING"
HDL_TAP"TRUE";
"B \NAC \NWC"3;
"S \NAC"
BN"1"87;
%"TAP"
"1","(-3425,2350)","0","mstr_standard","I237";
;
CDS_LIB"mstr_standard"
BODY_TYPE"PLUMBING"
HDL_TAP"TRUE";
"B \NAC \NWC"3;
"S \NAC"
BN"2"104;
%"TAP"
"1","(-3425,2300)","0","mstr_standard","I238";
;
CDS_LIB"mstr_standard"
BODY_TYPE"PLUMBING"
HDL_TAP"TRUE";
"B \NAC \NWC"3;
"S \NAC"
BN"3"103;
%"TAP"
"1","(-3425,2250)","0","mstr_standard","I239";
;
CDS_LIB"mstr_standard"
BODY_TYPE"PLUMBING"
HDL_TAP"TRUE";
"B \NAC \NWC"3;
"S \NAC"
BN"4"102;
%"TAP"
"1","(-3425,2200)","0","mstr_standard","I240";
;
CDS_LIB"mstr_standard"
BODY_TYPE"PLUMBING"
HDL_TAP"TRUE";
"B \NAC \NWC"3;
"S \NAC"
BN"5"100;
%"TAP"
"1","(-3425,2150)","0","mstr_standard","I241";
;
CDS_LIB"mstr_standard"
BODY_TYPE"PLUMBING"
HDL_TAP"TRUE";
"B \NAC \NWC"3;
"S \NAC"
BN"6"98;
%"TAP"
"1","(-3425,2100)","0","mstr_standard","I242";
;
CDS_LIB"mstr_standard"
BODY_TYPE"PLUMBING"
HDL_TAP"TRUE";
"B \NAC \NWC"3;
"S \NAC"
BN"7"97;
%"TAP"
"1","(-3425,1950)","0","mstr_standard","I244";
;
CDS_LIB"mstr_standard"
BODY_TYPE"PLUMBING"
HDL_TAP"TRUE";
"B \NAC \NWC"4;
"S \NAC"
BN"1"85;
%"TAP"
"1","(-3425,2000)","0","mstr_standard","I245";
;
CDS_LIB"mstr_standard"
BODY_TYPE"PLUMBING"
HDL_TAP"TRUE";
"B \NAC \NWC"4;
"S \NAC"
BN"0"86;
%"TAP"
"1","(-3425,1900)","0","mstr_standard","I246";
;
CDS_LIB"mstr_standard"
BODY_TYPE"PLUMBING"
HDL_TAP"TRUE";
"B \NAC \NWC"4;
"S \NAC"
BN"2"84;
%"TAP"
"1","(-3425,1800)","0","mstr_standard","I247";
;
CDS_LIB"mstr_standard"
BODY_TYPE"PLUMBING"
HDL_TAP"TRUE";
"B \NAC \NWC"4;
"S \NAC"
BN"4"82;
%"TAP"
"1","(-3425,1850)","0","mstr_standard","I248";
;
CDS_LIB"mstr_standard"
BODY_TYPE"PLUMBING"
HDL_TAP"TRUE";
"B \NAC \NWC"4;
"S \NAC"
BN"3"83;
%"TAP"
"1","(-3425,1700)","0","mstr_standard","I249";
;
CDS_LIB"mstr_standard"
BODY_TYPE"PLUMBING"
HDL_TAP"TRUE";
"B \NAC \NWC"4;
"S \NAC"
BN"6"80;
%"TAP"
"1","(-3425,1750)","0","mstr_standard","I250";
;
CDS_LIB"mstr_standard"
BODY_TYPE"PLUMBING"
HDL_TAP"TRUE";
"B \NAC \NWC"4;
"S \NAC"
BN"5"81;
%"TAP"
"1","(-3425,1650)","0","mstr_standard","I251";
;
CDS_LIB"mstr_standard"
BODY_TYPE"PLUMBING"
HDL_TAP"TRUE";
"B \NAC \NWC"4;
"S \NAC"
BN"7"79;
%"TAP"
"1","(-5850,6050)","2","mstr_standard","I252";
;
CDS_LIB"mstr_standard"
BODY_TYPE"PLUMBING"
HDL_TAP"TRUE";
"B \NAC \NWC"5;
"S \NAC"
BN"0"73;
%"TAP"
"1","(-5850,5950)","2","mstr_standard","I253";
;
CDS_LIB"mstr_standard"
BODY_TYPE"PLUMBING"
HDL_TAP"TRUE";
"B \NAC \NWC"5;
"S \NAC"
BN"1"71;
%"TAP"
"1","(-5850,5850)","2","mstr_standard","I254";
;
CDS_LIB"mstr_standard"
BODY_TYPE"PLUMBING"
HDL_TAP"TRUE";
"B \NAC \NWC"5;
"S \NAC"
BN"2"69;
%"TAP"
"1","(-5850,5750)","2","mstr_standard","I255";
;
CDS_LIB"mstr_standard"
BODY_TYPE"PLUMBING"
HDL_TAP"TRUE";
"B \NAC \NWC"5;
"S \NAC"
BN"3"67;
%"TAP"
"1","(-5850,5650)","2","mstr_standard","I256";
;
CDS_LIB"mstr_standard"
BODY_TYPE"PLUMBING"
HDL_TAP"TRUE";
"B \NAC \NWC"5;
"S \NAC"
BN"4"65;
%"TAP"
"1","(-6050,6000)","2","mstr_standard","I257";
;
CDS_LIB"mstr_standard"
BODY_TYPE"PLUMBING"
HDL_TAP"TRUE";
"B \NAC \NWC"9;
"S \NAC"
BN"0"78;
%"TAP"
"1","(-6050,5900)","2","mstr_standard","I258";
;
CDS_LIB"mstr_standard"
BODY_TYPE"PLUMBING"
HDL_TAP"TRUE";
"B \NAC \NWC"9;
"S \NAC"
BN"1"77;
%"TAP"
"1","(-6050,5800)","2","mstr_standard","I259";
;
CDS_LIB"mstr_standard"
BODY_TYPE"PLUMBING"
HDL_TAP"TRUE";
"B \NAC \NWC"9;
"S \NAC"
BN"2"76;
%"TAP"
"1","(-6050,5700)","2","mstr_standard","I260";
;
CDS_LIB"mstr_standard"
BODY_TYPE"PLUMBING"
HDL_TAP"TRUE";
"B \NAC \NWC"9;
"S \NAC"
BN"3"75;
%"TAP"
"1","(-5850,5550)","2","mstr_standard","I261";
;
CDS_LIB"mstr_standard"
BODY_TYPE"PLUMBING"
HDL_TAP"TRUE";
"B \NAC \NWC"5;
"S \NAC"
BN"5"64;
%"TAP"
"1","(-5850,5450)","2","mstr_standard","I262";
;
CDS_LIB"mstr_standard"
BODY_TYPE"PLUMBING"
HDL_TAP"TRUE";
"B \NAC \NWC"5;
"S \NAC"
BN"6"63;
%"TAP"
"1","(-5850,5350)","2","mstr_standard","I263";
;
CDS_LIB"mstr_standard"
BODY_TYPE"PLUMBING"
HDL_TAP"TRUE";
"B \NAC \NWC"5;
"S \NAC"
BN"7"62;
%"TAP"
"1","(-5850,5250)","2","mstr_standard","I264";
;
CDS_LIB"mstr_standard"
BODY_TYPE"PLUMBING"
HDL_TAP"TRUE";
"B \NAC \NWC"5;
"S \NAC"
BN"8"61;
%"TAP"
"1","(-5850,5150)","2","mstr_standard","I265";
;
CDS_LIB"mstr_standard"
BODY_TYPE"PLUMBING"
HDL_TAP"TRUE";
"B \NAC \NWC"5;
"S \NAC"
BN"9"60;
%"TAP"
"1","(-6050,5600)","2","mstr_standard","I266";
;
CDS_LIB"mstr_standard"
BODY_TYPE"PLUMBING"
HDL_TAP"TRUE";
"B \NAC \NWC"9;
"S \NAC"
BN"4"74;
%"TAP"
"1","(-6050,5500)","2","mstr_standard","I267";
;
CDS_LIB"mstr_standard"
BODY_TYPE"PLUMBING"
HDL_TAP"TRUE";
"B \NAC \NWC"9;
"S \NAC"
BN"5"72;
%"TAP"
"1","(-6050,5400)","2","mstr_standard","I268";
;
CDS_LIB"mstr_standard"
BODY_TYPE"PLUMBING"
HDL_TAP"TRUE";
"B \NAC \NWC"9;
"S \NAC"
BN"6"70;
%"TAP"
"1","(-6050,5300)","2","mstr_standard","I269";
;
CDS_LIB"mstr_standard"
BODY_TYPE"PLUMBING"
HDL_TAP"TRUE";
"B \NAC \NWC"9;
"S \NAC"
BN"7"68;
%"TAP"
"1","(-6050,5200)","2","mstr_standard","I270";
;
CDS_LIB"mstr_standard"
BODY_TYPE"PLUMBING"
HDL_TAP"TRUE";
"B \NAC \NWC"9;
"S \NAC"
BN"8"66;
%"TAP"
"1","(-5850,5000)","2","mstr_standard","I271";
;
CDS_LIB"mstr_standard"
BODY_TYPE"PLUMBING"
HDL_TAP"TRUE";
"B \NAC \NWC"6;
"S \NAC"
BN"0"49;
%"TAP"
"1","(-5850,4900)","2","mstr_standard","I272";
;
CDS_LIB"mstr_standard"
BODY_TYPE"PLUMBING"
HDL_TAP"TRUE";
"B \NAC \NWC"6;
"S \NAC"
BN"1"47;
%"TAP"
"1","(-5850,4800)","2","mstr_standard","I273";
;
CDS_LIB"mstr_standard"
BODY_TYPE"PLUMBING"
HDL_TAP"TRUE";
"B \NAC \NWC"6;
"S \NAC"
BN"2"45;
%"TAP"
"1","(-5850,4700)","2","mstr_standard","I274";
;
CDS_LIB"mstr_standard"
BODY_TYPE"PLUMBING"
HDL_TAP"TRUE";
"B \NAC \NWC"6;
"S \NAC"
BN"3"43;
%"TAP"
"1","(-6050,5100)","2","mstr_standard","I275";
;
CDS_LIB"mstr_standard"
BODY_TYPE"PLUMBING"
HDL_TAP"TRUE";
"B \NAC \NWC"9;
"S \NAC"
BN"9"51;
%"TAP"
"1","(-6050,4950)","2","mstr_standard","I276";
;
CDS_LIB"mstr_standard"
BODY_TYPE"PLUMBING"
HDL_TAP"TRUE";
"B \NAC \NWC"10;
"S \NAC"
BN"0"55;
%"TAP"
"1","(-6050,4850)","2","mstr_standard","I277";
;
CDS_LIB"mstr_standard"
BODY_TYPE"PLUMBING"
HDL_TAP"TRUE";
"B \NAC \NWC"10;
"S \NAC"
BN"1"54;
%"TAP"
"1","(-6050,4750)","2","mstr_standard","I278";
;
CDS_LIB"mstr_standard"
BODY_TYPE"PLUMBING"
HDL_TAP"TRUE";
"B \NAC \NWC"10;
"S \NAC"
BN"2"53;
%"TAP"
"1","(-6050,4650)","2","mstr_standard","I279";
;
CDS_LIB"mstr_standard"
BODY_TYPE"PLUMBING"
HDL_TAP"TRUE";
"B \NAC \NWC"10;
"S \NAC"
BN"3"52;
%"TAP"
"1","(-5850,4600)","2","mstr_standard","I280";
;
CDS_LIB"mstr_standard"
BODY_TYPE"PLUMBING"
HDL_TAP"TRUE";
"B \NAC \NWC"6;
"S \NAC"
BN"4"41;
%"TAP"
"1","(-5850,4500)","2","mstr_standard","I281";
;
CDS_LIB"mstr_standard"
BODY_TYPE"PLUMBING"
HDL_TAP"TRUE";
"B \NAC \NWC"6;
"S \NAC"
BN"5"59;
%"TAP"
"1","(-5850,4400)","2","mstr_standard","I282";
;
CDS_LIB"mstr_standard"
BODY_TYPE"PLUMBING"
HDL_TAP"TRUE";
"B \NAC \NWC"6;
"S \NAC"
BN"6"58;
%"TAP"
"1","(-5850,4300)","2","mstr_standard","I283";
;
CDS_LIB"mstr_standard"
BODY_TYPE"PLUMBING"
HDL_TAP"TRUE";
"B \NAC \NWC"6;
"S \NAC"
BN"7"57;
%"TAP"
"1","(-5850,4200)","2","mstr_standard","I284";
;
CDS_LIB"mstr_standard"
BODY_TYPE"PLUMBING"
HDL_TAP"TRUE";
"B \NAC \NWC"6;
"S \NAC"
BN"8"56;
%"TAP"
"1","(-5850,4100)","2","mstr_standard","I285";
;
CDS_LIB"mstr_standard"
BODY_TYPE"PLUMBING"
HDL_TAP"TRUE";
"B \NAC \NWC"6;
"S \NAC"
BN"9"40;
%"TAP"
"1","(-6050,4550)","2","mstr_standard","I286";
;
CDS_LIB"mstr_standard"
BODY_TYPE"PLUMBING"
HDL_TAP"TRUE";
"B \NAC \NWC"10;
"S \NAC"
BN"4"50;
%"TAP"
"1","(-6050,4450)","2","mstr_standard","I287";
;
CDS_LIB"mstr_standard"
BODY_TYPE"PLUMBING"
HDL_TAP"TRUE";
"B \NAC \NWC"10;
"S \NAC"
BN"5"48;
%"TAP"
"1","(-6050,4350)","2","mstr_standard","I288";
;
CDS_LIB"mstr_standard"
BODY_TYPE"PLUMBING"
HDL_TAP"TRUE";
"B \NAC \NWC"10;
"S \NAC"
BN"6"46;
%"TAP"
"1","(-6050,4250)","2","mstr_standard","I289";
;
CDS_LIB"mstr_standard"
BODY_TYPE"PLUMBING"
HDL_TAP"TRUE";
"B \NAC \NWC"10;
"S \NAC"
BN"7"44;
%"TAP"
"1","(-6050,4150)","2","mstr_standard","I290";
;
CDS_LIB"mstr_standard"
BODY_TYPE"PLUMBING"
HDL_TAP"TRUE";
"B \NAC \NWC"10;
"S \NAC"
BN"8"42;
%"TAP"
"1","(-6050,4050)","2","mstr_standard","I295";
;
CDS_LIB"mstr_standard"
BODY_TYPE"PLUMBING"
HDL_TAP"TRUE";
"B \NAC \NWC"10;
"S \NAC"
BN"9"39;
%"TAP"
"1","(-6050,3900)","2","mstr_standard","I296";
;
CDS_LIB"mstr_standard"
BODY_TYPE"PLUMBING"
HDL_TAP"TRUE";
"B \NAC \NWC"7;
"S \NAC"
BN"0"38;
%"TAP"
"1","(-6050,3850)","2","mstr_standard","I297";
;
CDS_LIB"mstr_standard"
BODY_TYPE"PLUMBING"
HDL_TAP"TRUE";
"B \NAC \NWC"7;
"S \NAC"
BN"1"36;
%"TAP"
"1","(-6050,3800)","2","mstr_standard","I298";
;
CDS_LIB"mstr_standard"
BODY_TYPE"PLUMBING"
HDL_TAP"TRUE";
"B \NAC \NWC"7;
"S \NAC"
BN"2"34;
%"TAP"
"1","(-6050,3750)","2","mstr_standard","I299";
;
CDS_LIB"mstr_standard"
BODY_TYPE"PLUMBING"
HDL_TAP"TRUE";
"B \NAC \NWC"7;
"S \NAC"
BN"3"32;
%"TAP"
"1","(-6050,3700)","2","mstr_standard","I300";
;
CDS_LIB"mstr_standard"
BODY_TYPE"PLUMBING"
HDL_TAP"TRUE";
"B \NAC \NWC"7;
"S \NAC"
BN"4"30;
%"TAP"
"1","(-6050,3650)","2","mstr_standard","I301";
;
CDS_LIB"mstr_standard"
BODY_TYPE"PLUMBING"
HDL_TAP"TRUE";
"B \NAC \NWC"7;
"S \NAC"
BN"5"28;
%"TAP"
"1","(-6050,3600)","2","mstr_standard","I302";
;
CDS_LIB"mstr_standard"
BODY_TYPE"PLUMBING"
HDL_TAP"TRUE";
"B \NAC \NWC"7;
"S \NAC"
BN"6"26;
%"TAP"
"1","(-6050,3500)","2","mstr_standard","I303";
;
CDS_LIB"mstr_standard"
BODY_TYPE"PLUMBING"
HDL_TAP"TRUE";
"B \NAC \NWC"8;
"S \NAC"
BN"0"37;
%"TAP"
"1","(-6050,3450)","2","mstr_standard","I304";
;
CDS_LIB"mstr_standard"
BODY_TYPE"PLUMBING"
HDL_TAP"TRUE";
"B \NAC \NWC"8;
"S \NAC"
BN"1"35;
%"TAP"
"1","(-6050,3400)","2","mstr_standard","I305";
;
CDS_LIB"mstr_standard"
BODY_TYPE"PLUMBING"
HDL_TAP"TRUE";
"B \NAC \NWC"8;
"S \NAC"
BN"2"33;
%"TAP"
"1","(-6050,3350)","2","mstr_standard","I306";
;
CDS_LIB"mstr_standard"
BODY_TYPE"PLUMBING"
HDL_TAP"TRUE";
"B \NAC \NWC"8;
"S \NAC"
BN"3"31;
%"TAP"
"1","(-6050,3300)","2","mstr_standard","I307";
;
CDS_LIB"mstr_standard"
BODY_TYPE"PLUMBING"
HDL_TAP"TRUE";
"B \NAC \NWC"8;
"S \NAC"
BN"4"29;
%"TAP"
"1","(-6050,3250)","2","mstr_standard","I308";
;
CDS_LIB"mstr_standard"
BODY_TYPE"PLUMBING"
HDL_TAP"TRUE";
"B \NAC \NWC"8;
"S \NAC"
BN"5"27;
%"TAP"
"1","(-6050,3200)","2","mstr_standard","I309";
;
CDS_LIB"mstr_standard"
BODY_TYPE"PLUMBING"
HDL_TAP"TRUE";
"B \NAC \NWC"8;
"S \NAC"
BN"6"25;
%"Q_RES"
"1","(-6725,2200)","0","pure_quanta","I322";
;
LOCATION"R506"
$SEC"1"
CDS_SEC"1"
TOLERANCE"1%"
VALUE"15   "
PART_NUMBER"CS01502FB11"
PACK_TYPE"0402LF"
CDS_LIB"pure_quanta"
WATTAGE"1/16W"
MATERIAL"CHIP";
"B"
$PN"2"13;
"A"
$PN"1"11;
END.
